(kicad_pcb
	(version 20260206)
	(generator "pcbnew")
	(generator_version "10.0")
	(general
		(thickness 1.6)
		(legacy_teardrops no)
	)
	(paper "A4")
	(title_block
		(title "04192023_DAF0TMB3IC0_F0TG_MB_C_brd_V02_OCP.brd")
		(comment 1 "Grand Teton / footprints 1147-1152 of 8354")
	)
	(layers
		(0 "F.Cu" signal "TOP")
		(4 "In1.Cu" signal "GND")
		(6 "In2.Cu" signal "IN1")
		(8 "In3.Cu" signal "GND1")
		(10 "In4.Cu" signal "IN2")
		(12 "In5.Cu" signal "GND2")
		(14 "In6.Cu" signal "IN3")
		(16 "In7.Cu" signal "GND3")
		(18 "In8.Cu" signal "VCC")
		(20 "In9.Cu" signal "VCC1")
		(22 "In10.Cu" signal "GND4")
		(24 "In11.Cu" signal "IN4")
		(26 "In12.Cu" signal "GND5")
		(28 "In13.Cu" signal "IN5")
		(30 "In14.Cu" signal "GND6")
		(32 "In15.Cu" signal "IN6")
		(34 "In16.Cu" signal "GND7")
		(2 "B.Cu" signal "BOTTOM")
		(9 "F.Adhes" user "F.Adhesive")
		(11 "B.Adhes" user "B.Adhesive")
		(13 "F.Paste" user "Package Geometry/Pastemask Top")
		(15 "B.Paste" user "Package Geometry/Pastemask Bottom")
		(5 "F.SilkS" user "Ref Des/Silkscreen Top")
		(7 "B.SilkS" user "Ref Des/Silkscreen Bottom")
		(1 "F.Mask" user "Board Geometry/Soldermask Top")
		(3 "B.Mask" user "Board Geometry/Soldermask Bottom")
		(17 "Dwgs.User" user "User.Drawings")
		(19 "Cmts.User" user "User.Comments")
		(21 "Eco1.User" user "User.Eco1")
		(23 "Eco2.User" user "User.Eco2")
		(25 "Edge.Cuts" user "Board Geometry/Outline")
		(27 "Margin" user)
		(31 "F.CrtYd" user "Package Geometry/Place Bound Top")
		(29 "B.CrtYd" user "Package Geometry/Place Bound Bottom")
		(35 "F.Fab" user "Ref Des/Assembly Top")
		(33 "B.Fab" user "Ref Des/Assembly Bottom")
	)
	(footprint ""
		(layer "F.Cu")
		(at 459.579726 -98.514408)
		(property "Reference" "U66"
			(at -4.11226 -1.882648 0)
			(unlocked yes)
			(layer "F.SilkS")
			(effects
				(font
					(size 0.7874 0.5842)
					(thickness 0.1524)
				)
				(justify left)
			)
		)
		(property "Value" ""
			(at 0 0 0)
			(layer "F.Fab")
			(effects
				(font
					(size 1.27 1.27)
				)
			)
		)
		(duplicate_pad_numbers_are_jumpers no)
		(fp_line
			(start -1.400048 1.100074)
			(end -1.400048 -1.100074)
			(stroke
				(width 0.1524)
				(type default)
			)
			(layer "F.SilkS")
		)
		(fp_line
			(start 1.400048 -1.100074)
			(end -1.400048 -1.100074)
			(stroke
				(width 0.1524)
				(type default)
			)
			(layer "F.SilkS")
		)
		(fp_line
			(start 1.400048 -1.100074)
			(end 1.400048 1.100074)
			(stroke
				(width 0.1524)
				(type default)
			)
			(layer "F.SilkS")
		)
		(fp_line
			(start 1.400048 1.100074)
			(end -1.400048 1.100074)
			(stroke
				(width 0.1524)
				(type default)
			)
			(layer "F.SilkS")
		)
		(fp_poly
			(pts
				(xy -1.559052 -2.258314) (xy -0.543052 -2.258314) (xy -1.051052 -1.242314)
			)
			(stroke
				(width 0)
				(type default)
			)
			(fill yes)
			(layer "F.SilkS")
		)
		(fp_line
			(start -0.674878 -1.100074)
			(end 0.674878 -1.100074)
			(stroke
				(width 0.1)
				(type default)
			)
			(layer "F.Fab")
		)
		(fp_line
			(start -0.674878 1.100074)
			(end -0.674878 -1.100074)
			(stroke
				(width 0.1)
				(type default)
			)
			(layer "F.Fab")
		)
		(fp_line
			(start 0.674878 -1.100074)
			(end 0.674878 1.100074)
			(stroke
				(width 0.1)
				(type default)
			)
			(layer "F.Fab")
		)
		(fp_line
			(start 0.674878 1.100074)
			(end -0.674878 1.100074)
			(stroke
				(width 0.1)
				(type default)
			)
			(layer "F.Fab")
		)
		(fp_poly
			(pts
				(xy -1.590548 -0.649986) (xy -2.606548 -1.157986) (xy -2.606548 -0.141986)
			)
			(stroke
				(width 0)
				(type default)
			)
			(fill yes)
			(layer "F.Fab")
		)
		(pad "1" smd rect
			(at -0.94996 -0.649986 270)
			(size 0.4318 0.6096)
			(layers "F.Cu" "F.Mask" "F.Paste")
			(net "OCP_SFF_AUX_PWR_EN_R1")
		)
		(pad "2" smd rect
			(at -0.94996 0 270)
			(size 0.4318 0.6096)
			(layers "F.Cu" "F.Mask" "F.Paste")
			(net "FM_OCP_SFF_PWR_GOOD")
		)
		(pad "3" smd rect
			(at -0.94996 0.649986 270)
			(size 0.4318 0.6096)
			(layers "F.Cu" "F.Mask" "F.Paste")
			(net "GND")
		)
		(pad "4" smd rect
			(at 0.94996 0.649986 270)
			(size 0.4318 0.6096)
			(layers "F.Cu" "F.Mask" "F.Paste")
			(net "FB_BMC_ISOLATE_R1")
		)
		(pad "5" smd rect
			(at 0.94996 -0.649986 270)
			(size 0.4318 0.6096)
			(layers "F.Cu" "F.Mask" "F.Paste")
			(net "P3V3_AUX")
		)
	)
	(footprint ""
		(layer "F.Cu")
		(at 249.713496 -48.094138)
		(property "Reference" "PC2217"
			(at 0 0 0)
			(layer "F.SilkS")
			(hide yes)
			(effects
				(font
					(size 1.27 1.27)
				)
			)
		)
		(property "Value" ""
			(at 0 0 0)
			(layer "F.Fab")
			(effects
				(font
					(size 1.27 1.27)
				)
			)
		)
		(duplicate_pad_numbers_are_jumpers no)
		(fp_line
			(start -0.7874 -0.4064)
			(end 0.7874 -0.4064)
			(stroke
				(width 0.1524)
				(type default)
			)
			(layer "F.SilkS")
		)
		(fp_line
			(start -0.7874 0.4064)
			(end -0.7874 -0.4064)
			(stroke
				(width 0.1524)
				(type default)
			)
			(layer "F.SilkS")
		)
		(fp_line
			(start 0.7874 -0.4064)
			(end 0.7874 0.4064)
			(stroke
				(width 0.1524)
				(type default)
			)
			(layer "F.SilkS")
		)
		(fp_line
			(start 0.7874 0.4064)
			(end -0.7874 0.4064)
			(stroke
				(width 0.1524)
				(type default)
			)
			(layer "F.SilkS")
		)
		(fp_line
			(start -0.67945 -0.305054)
			(end -0.12065 -0.305054)
			(stroke
				(width 0.1)
				(type default)
			)
			(layer "F.Fab")
		)
		(fp_line
			(start -0.67945 0.3048)
			(end -0.67945 -0.305054)
			(stroke
				(width 0.1)
				(type default)
			)
			(layer "F.Fab")
		)
		(fp_line
			(start -0.12065 -0.305054)
			(end -0.12065 -0.2794)
			(stroke
				(width 0.1)
				(type default)
			)
			(layer "F.Fab")
		)
		(fp_line
			(start -0.12065 -0.2794)
			(end 0.12065 -0.2794)
			(stroke
				(width 0.1)
				(type default)
			)
			(layer "F.Fab")
		)
		(fp_line
			(start -0.12065 0.2794)
			(end -0.12065 0.3048)
			(stroke
				(width 0.1)
				(type default)
			)
			(layer "F.Fab")
		)
		(fp_line
			(start -0.12065 0.3048)
			(end -0.67945 0.3048)
			(stroke
				(width 0.1)
				(type default)
			)
			(layer "F.Fab")
		)
		(fp_line
			(start 0.120396 0.2794)
			(end -0.12065 0.2794)
			(stroke
				(width 0.1)
				(type default)
			)
			(layer "F.Fab")
		)
		(fp_line
			(start 0.120396 0.3048)
			(end 0.120396 0.2794)
			(stroke
				(width 0.1)
				(type default)
			)
			(layer "F.Fab")
		)
		(fp_line
			(start 0.12065 -0.3048)
			(end 0.67945 -0.3048)
			(stroke
				(width 0.1)
				(type default)
			)
			(layer "F.Fab")
		)
		(fp_line
			(start 0.12065 -0.2794)
			(end 0.12065 -0.3048)
			(stroke
				(width 0.1)
				(type default)
			)
			(layer "F.Fab")
		)
		(fp_line
			(start 0.67945 -0.3048)
			(end 0.67945 0.3048)
			(stroke
				(width 0.1)
				(type default)
			)
			(layer "F.Fab")
		)
		(fp_line
			(start 0.67945 0.3048)
			(end 0.120396 0.3048)
			(stroke
				(width 0.1)
				(type default)
			)
			(layer "F.Fab")
		)
		(pad "1" smd circle
			(at -0.40005 0)
			(size 0 0)
			(layers "F.Cu" "F.Mask" "F.Paste")
			(net "P12V_E1S_0")
		)
		(pad "2" smd circle
			(at 0.40005 0)
			(size 0 0)
			(layers "F.Cu" "F.Mask" "F.Paste")
			(net "GND")
		)
	)
	(footprint ""
		(layer "F.Cu")
		(at 312.342022 -33.715706 180)
		(property "Reference" "R3864"
			(at 0 0 180)
			(layer "F.SilkS")
			(hide yes)
			(effects
				(font
					(size 1.27 1.27)
				)
			)
		)
		(property "Value" ""
			(at 0 0 180)
			(layer "F.Fab")
			(effects
				(font
					(size 1.27 1.27)
				)
			)
		)
		(duplicate_pad_numbers_are_jumpers no)
		(fp_line
			(start 0.7874 0.4064)
			(end -0.7874 0.4064)
			(stroke
				(width 0.1524)
				(type default)
			)
			(layer "F.SilkS")
		)
		(fp_line
			(start 0.7874 -0.4064)
			(end 0.7874 0.4064)
			(stroke
				(width 0.1524)
				(type default)
			)
			(layer "F.SilkS")
		)
		(fp_line
			(start -0.7874 0.4064)
			(end -0.7874 -0.4064)
			(stroke
				(width 0.1524)
				(type default)
			)
			(layer "F.SilkS")
		)
		(fp_line
			(start -0.7874 -0.4064)
			(end 0.7874 -0.4064)
			(stroke
				(width 0.1524)
				(type default)
			)
			(layer "F.SilkS")
		)
		(fp_line
			(start 0.67945 0.3048)
			(end 0.120396 0.3048)
			(stroke
				(width 0.1)
				(type default)
			)
			(layer "F.Fab")
		)
		(fp_line
			(start 0.67945 -0.3048)
			(end 0.67945 0.3048)
			(stroke
				(width 0.1)
				(type default)
			)
			(layer "F.Fab")
		)
		(fp_line
			(start 0.12065 -0.2794)
			(end 0.12065 -0.3048)
			(stroke
				(width 0.1)
				(type default)
			)
			(layer "F.Fab")
		)
		(fp_line
			(start 0.12065 -0.3048)
			(end 0.67945 -0.3048)
			(stroke
				(width 0.1)
				(type default)
			)
			(layer "F.Fab")
		)
		(fp_line
			(start 0.120396 0.3048)
			(end 0.120396 0.2794)
			(stroke
				(width 0.1)
				(type default)
			)
			(layer "F.Fab")
		)
		(fp_line
			(start 0.120396 0.2794)
			(end -0.12065 0.2794)
			(stroke
				(width 0.1)
				(type default)
			)
			(layer "F.Fab")
		)
		(fp_line
			(start -0.12065 0.3048)
			(end -0.67945 0.3048)
			(stroke
				(width 0.1)
				(type default)
			)
			(layer "F.Fab")
		)
		(fp_line
			(start -0.12065 0.2794)
			(end -0.12065 0.3048)
			(stroke
				(width 0.1)
				(type default)
			)
			(layer "F.Fab")
		)
		(fp_line
			(start -0.12065 -0.2794)
			(end 0.12065 -0.2794)
			(stroke
				(width 0.1)
				(type default)
			)
			(layer "F.Fab")
		)
		(fp_line
			(start -0.12065 -0.305054)
			(end -0.12065 -0.2794)
			(stroke
				(width 0.1)
				(type default)
			)
			(layer "F.Fab")
		)
		(fp_line
			(start -0.67945 0.3048)
			(end -0.67945 -0.305054)
			(stroke
				(width 0.1)
				(type default)
			)
			(layer "F.Fab")
		)
		(fp_line
			(start -0.67945 -0.305054)
			(end -0.12065 -0.305054)
			(stroke
				(width 0.1)
				(type default)
			)
			(layer "F.Fab")
		)
		(pad "1" smd rect
			(at -0.40005 0)
			(size 0.4572 0.508)
			(layers "F.Cu" "F.Mask" "F.Paste")
			(net "P12V_OCP_SFF_ISENSE_MPS_MAM")
		)
		(pad "2" smd rect
			(at 0.40005 0)
			(size 0.4572 0.508)
			(layers "F.Cu" "F.Mask" "F.Paste")
			(net "P12V_OCP_SFF_ISENSE_MAM")
		)
	)
	(footprint ""
		(layer "F.Cu")
		(at 35.132772 -433.112164 180)
		(property "Reference" "R3524"
			(at 0 0 180)
			(layer "F.SilkS")
			(hide yes)
			(effects
				(font
					(size 1.27 1.27)
				)
			)
		)
		(property "Value" ""
			(at 0 0 180)
			(layer "F.Fab")
			(effects
				(font
					(size 1.27 1.27)
				)
			)
		)
		(duplicate_pad_numbers_are_jumpers no)
		(fp_line
			(start 0.7874 0.4064)
			(end -0.7874 0.4064)
			(stroke
				(width 0.1524)
				(type default)
			)
			(layer "F.SilkS")
		)
		(fp_line
			(start 0.7874 -0.4064)
			(end 0.7874 0.4064)
			(stroke
				(width 0.1524)
				(type default)
			)
			(layer "F.SilkS")
		)
		(fp_line
			(start -0.7874 0.4064)
			(end -0.7874 -0.4064)
			(stroke
				(width 0.1524)
				(type default)
			)
			(layer "F.SilkS")
		)
		(fp_line
			(start -0.7874 -0.4064)
			(end 0.7874 -0.4064)
			(stroke
				(width 0.1524)
				(type default)
			)
			(layer "F.SilkS")
		)
		(fp_line
			(start 0.67945 0.3048)
			(end 0.120396 0.3048)
			(stroke
				(width 0.1)
				(type default)
			)
			(layer "F.Fab")
		)
		(fp_line
			(start 0.67945 -0.3048)
			(end 0.67945 0.3048)
			(stroke
				(width 0.1)
				(type default)
			)
			(layer "F.Fab")
		)
		(fp_line
			(start 0.12065 -0.2794)
			(end 0.12065 -0.3048)
			(stroke
				(width 0.1)
				(type default)
			)
			(layer "F.Fab")
		)
		(fp_line
			(start 0.12065 -0.3048)
			(end 0.67945 -0.3048)
			(stroke
				(width 0.1)
				(type default)
			)
			(layer "F.Fab")
		)
		(fp_line
			(start 0.120396 0.3048)
			(end 0.120396 0.2794)
			(stroke
				(width 0.1)
				(type default)
			)
			(layer "F.Fab")
		)
		(fp_line
			(start 0.120396 0.2794)
			(end -0.12065 0.2794)
			(stroke
				(width 0.1)
				(type default)
			)
			(layer "F.Fab")
		)
		(fp_line
			(start -0.12065 0.3048)
			(end -0.67945 0.3048)
			(stroke
				(width 0.1)
				(type default)
			)
			(layer "F.Fab")
		)
		(fp_line
			(start -0.12065 0.2794)
			(end -0.12065 0.3048)
			(stroke
				(width 0.1)
				(type default)
			)
			(layer "F.Fab")
		)
		(fp_line
			(start -0.12065 -0.2794)
			(end 0.12065 -0.2794)
			(stroke
				(width 0.1)
				(type default)
			)
			(layer "F.Fab")
		)
		(fp_line
			(start -0.12065 -0.305054)
			(end -0.12065 -0.2794)
			(stroke
				(width 0.1)
				(type default)
			)
			(layer "F.Fab")
		)
		(fp_line
			(start -0.67945 0.3048)
			(end -0.67945 -0.305054)
			(stroke
				(width 0.1)
				(type default)
			)
			(layer "F.Fab")
		)
		(fp_line
			(start -0.67945 -0.305054)
			(end -0.12065 -0.305054)
			(stroke
				(width 0.1)
				(type default)
			)
			(layer "F.Fab")
		)
		(pad "1" smd circle
			(at -0.40005 0 180)
			(size 0 0)
			(layers "F.Cu" "F.Mask" "F.Paste")
			(net "P3V3_AUX")
		)
		(pad "2" smd circle
			(at 0.40005 0 180)
			(size 0 0)
			(layers "F.Cu" "F.Mask" "F.Paste")
			(net "SMB_1_BMC_GPU_BUF_R_SDA")
		)
	)
	(footprint ""
		(layer "F.Cu")
		(at 19.400012 -358.30637 -90)
		(property "Reference" "C8356"
			(at 0 0 270)
			(layer "F.SilkS")
			(hide yes)
			(effects
				(font
					(size 1.27 1.27)
				)
			)
		)
		(property "Value" ""
			(at 0 0 270)
			(layer "F.Fab")
			(effects
				(font
					(size 1.27 1.27)
				)
			)
		)
		(duplicate_pad_numbers_are_jumpers no)
		(fp_line
			(start -0.7874 0.4064)
			(end -0.7874 -0.4064)
			(stroke
				(width 0.1524)
				(type default)
			)
			(layer "F.SilkS")
		)
		(fp_line
			(start 0.7874 0.4064)
			(end -0.7874 0.4064)
			(stroke
				(width 0.1524)
				(type default)
			)
			(layer "F.SilkS")
		)
		(fp_line
			(start -0.7874 -0.4064)
			(end 0.7874 -0.4064)
			(stroke
				(width 0.1524)
				(type default)
			)
			(layer "F.SilkS")
		)
		(fp_line
			(start 0.7874 -0.4064)
			(end 0.7874 0.4064)
			(stroke
				(width 0.1524)
				(type default)
			)
			(layer "F.SilkS")
		)
		(fp_line
			(start -0.67945 0.3048)
			(end -0.67945 -0.305054)
			(stroke
				(width 0.1)
				(type default)
			)
			(layer "F.Fab")
		)
		(fp_line
			(start -0.12065 0.3048)
			(end -0.67945 0.3048)
			(stroke
				(width 0.1)
				(type default)
			)
			(layer "F.Fab")
		)
		(fp_line
			(start 0.120396 0.3048)
			(end 0.120396 0.2794)
			(stroke
				(width 0.1)
				(type default)
			)
			(layer "F.Fab")
		)
		(fp_line
			(start 0.67945 0.3048)
			(end 0.120396 0.3048)
			(stroke
				(width 0.1)
				(type default)
			)
			(layer "F.Fab")
		)
		(fp_line
			(start -0.12065 0.2794)
			(end -0.12065 0.3048)
			(stroke
				(width 0.1)
				(type default)
			)
			(layer "F.Fab")
		)
		(fp_line
			(start 0.120396 0.2794)
			(end -0.12065 0.2794)
			(stroke
				(width 0.1)
				(type default)
			)
			(layer "F.Fab")
		)
		(fp_line
			(start -0.12065 -0.2794)
			(end 0.12065 -0.2794)
			(stroke
				(width 0.1)
				(type default)
			)
			(layer "F.Fab")
		)
		(fp_line
			(start 0.12065 -0.2794)
			(end 0.12065 -0.3048)
			(stroke
				(width 0.1)
				(type default)
			)
			(layer "F.Fab")
		)
		(fp_line
			(start 0.12065 -0.3048)
			(end 0.67945 -0.3048)
			(stroke
				(width 0.1)
				(type default)
			)
			(layer "F.Fab")
		)
		(fp_line
			(start 0.67945 -0.3048)
			(end 0.67945 0.3048)
			(stroke
				(width 0.1)
				(type default)
			)
			(layer "F.Fab")
		)
		(fp_line
			(start -0.67945 -0.305054)
			(end -0.12065 -0.305054)
			(stroke
				(width 0.1)
				(type default)
			)
			(layer "F.Fab")
		)
		(fp_line
			(start -0.12065 -0.305054)
			(end -0.12065 -0.2794)
			(stroke
				(width 0.1)
				(type default)
			)
			(layer "F.Fab")
		)
		(pad "1" smd circle
			(at -0.40005 0 270)
			(size 0 0)
			(layers "F.Cu" "F.Mask" "F.Paste")
			(net "PVDDIO_P1_EN_R")
		)
		(pad "2" smd circle
			(at 0.40005 0 270)
			(size 0 0)
			(layers "F.Cu" "F.Mask" "F.Paste")
			(net "GND")
		)
	)
	(footprint ""
		(layer "F.Cu")
		(at 132.213096 -370.57203 -90)
		(property "Reference" "C55"
			(at 0 0 270)
			(layer "F.SilkS")
			(hide yes)
			(effects
				(font
					(size 1.27 1.27)
				)
			)
		)
		(property "Value" ""
			(at 0 0 270)
			(layer "F.Fab")
			(effects
				(font
					(size 1.27 1.27)
				)
			)
		)
		(duplicate_pad_numbers_are_jumpers no)
		(fp_line
			(start -0.299974 0.150114)
			(end -0.299974 -0.150114)
			(stroke
				(width 0.1)
				(type default)
			)
			(layer "F.Fab")
		)
		(fp_line
			(start 0.299974 0.150114)
			(end -0.299974 0.150114)
			(stroke
				(width 0.1)
				(type default)
			)
			(layer "F.Fab")
		)
		(fp_line
			(start -0.299974 -0.150114)
			(end 0.299974 -0.150114)
			(stroke
				(width 0.1)
				(type default)
			)
			(layer "F.Fab")
		)
		(fp_line
			(start 0.299974 -0.150114)
			(end 0.299974 0.150114)
			(stroke
				(width 0.1)
				(type default)
			)
			(layer "F.Fab")
		)
		(pad "1" smd rect
			(at -0.2667 0 270)
			(size 0.3048 0.381)
			(layers "F.Cu" "F.Mask" "F.Paste")
			(net "P5E_CPU1_P3_TX_C_DP<12>")
		)
		(pad "2" smd rect
			(at 0.2667 0 270)
			(size 0.3048 0.381)
			(layers "F.Cu" "F.Mask" "F.Paste")
			(net "P5E_CPU1_P3_TX_DP<12>")
		)
	)
)
